# S9S_MB_2U (Grand Teton) — schematic netlist excerpt (pin names and nets, part order shuffled) for the footprints in the layout excerpt that follows; sources: Cadence DE-HDL packaged netlist, KiCad conversion of 03242023_DA0F0TMBIJ0_F0T_Motherboard_J_brd_V01_OCP.brd

R3147  Q_RES  10K 1% CHIP  pkg 0402LF  page 162 : A = P3V3_AUX ; B = HP_LVC3_OCP_V3_2_PRSNT2_N

OSC2  Q_OSC4P  25MHZ OSC  pkg SMLF  page 214
  OE  = PU_CLK25M_OSC_FPGA_EN
  GND  = GND
  \out\  = CLK_25M_OSC_FPGA_R
  VDD  = P3V3_AUX

(kicad_pcb
	(version 20260206)
	(generator "pcbnew")
	(generator_version "10.0")
	(general
		(thickness 1.6)
		(legacy_teardrops no)
	)
	(paper "A4")
	(title_block
		(title "03242023_DA0F0TMBIJ0_F0T_Motherboard_J_brd_V01_OCP.brd")
		(comment 1 "Grand Teton / footprints 2571-2572 of 6105")
	)
	(layers
		(0 "F.Cu" signal "TOP")
		(4 "In1.Cu" signal "GND")
		(6 "In2.Cu" signal "IN1")
		(8 "In3.Cu" signal "GND1")
		(10 "In4.Cu" signal "IN2")
		(12 "In5.Cu" signal "GND2")
		(14 "In6.Cu" signal "IN3")
		(16 "In7.Cu" signal "GND3")
		(18 "In8.Cu" signal "VCC")
		(20 "In9.Cu" signal "VCC1")
		(22 "In10.Cu" signal "GND4")
		(24 "In11.Cu" signal "IN4")
		(26 "In12.Cu" signal "GND5")
		(28 "In13.Cu" signal "IN5")
		(30 "In14.Cu" signal "GND6")
		(32 "In15.Cu" signal "IN6")
		(34 "In16.Cu" signal "GND7")
		(2 "B.Cu" signal "BOTTOM")
		(9 "F.Adhes" user "F.Adhesive")
		(11 "B.Adhes" user "B.Adhesive")
		(13 "F.Paste" user "Package Geometry/Pastemask Top")
		(15 "B.Paste" user "Package Geometry/Pastemask Bottom")
		(5 "F.SilkS" user "Ref Des/Silkscreen Top")
		(7 "B.SilkS" user "Ref Des/Silkscreen Bottom")
		(1 "F.Mask" user "Board Geometry/Soldermask Top")
		(3 "B.Mask" user "Board Geometry/Soldermask Bottom")
		(17 "Dwgs.User" user "User.Drawings")
		(19 "Cmts.User" user "User.Comments")
		(21 "Eco1.User" user "User.Eco1")
		(23 "Eco2.User" user "User.Eco2")
		(25 "Edge.Cuts" user "Board Geometry/Outline")
		(27 "Margin" user)
		(31 "F.CrtYd" user "Package Geometry/Place Bound Top")
		(29 "B.CrtYd" user "Package Geometry/Place Bound Bottom")
		(35 "F.Fab" user "Ref Des/Assembly Top")
		(33 "B.Fab" user "Ref Des/Assembly Bottom")
	)
	(footprint ""
		(layer "F.Cu")
		(at 31.856426 -70.83425 180)
		(property "Reference" "R3147"
			(at 0 0 180)
			(layer "F.SilkS")
			(hide yes)
			(effects
				(font
					(size 1.27 1.27)
				)
			)
		)
		(property "Value" ""
			(at 0 0 180)
			(layer "F.Fab")
			(effects
				(font
					(size 1.27 1.27)
				)
			)
		)
		(duplicate_pad_numbers_are_jumpers no)
		(fp_line
			(start 0.7874 0.4064)
			(end -0.7874 0.4064)
			(stroke
				(width 0.1524)
				(type default)
			)
			(layer "F.SilkS")
		)
		(fp_line
			(start 0.7874 -0.4064)
			(end 0.7874 0.4064)
			(stroke
				(width 0.1524)
				(type default)
			)
			(layer "F.SilkS")
		)
		(fp_line
			(start -0.7874 0.4064)
			(end -0.7874 -0.4064)
			(stroke
				(width 0.1524)
				(type default)
			)
			(layer "F.SilkS")
		)
		(fp_line
			(start -0.7874 -0.4064)
			(end 0.7874 -0.4064)
			(stroke
				(width 0.1524)
				(type default)
			)
			(layer "F.SilkS")
		)
		(fp_line
			(start 0.67945 0.3048)
			(end 0.120396 0.3048)
			(stroke
				(width 0.1)
				(type default)
			)
			(layer "F.Fab")
		)
		(fp_line
			(start 0.67945 -0.3048)
			(end 0.67945 0.3048)
			(stroke
				(width 0.1)
				(type default)
			)
			(layer "F.Fab")
		)
		(fp_line
			(start 0.12065 -0.2794)
			(end 0.12065 -0.3048)
			(stroke
				(width 0.1)
				(type default)
			)
			(layer "F.Fab")
		)
		(fp_line
			(start 0.12065 -0.3048)
			(end 0.67945 -0.3048)
			(stroke
				(width 0.1)
				(type default)
			)
			(layer "F.Fab")
		)
		(fp_line
			(start 0.120396 0.3048)
			(end 0.120396 0.2794)
			(stroke
				(width 0.1)
				(type default)
			)
			(layer "F.Fab")
		)
		(fp_line
			(start 0.120396 0.2794)
			(end -0.12065 0.2794)
			(stroke
				(width 0.1)
				(type default)
			)
			(layer "F.Fab")
		)
		(fp_line
			(start -0.12065 0.3048)
			(end -0.67945 0.3048)
			(stroke
				(width 0.1)
				(type default)
			)
			(layer "F.Fab")
		)
		(fp_line
			(start -0.12065 0.2794)
			(end -0.12065 0.3048)
			(stroke
				(width 0.1)
				(type default)
			)
			(layer "F.Fab")
		)
		(fp_line
			(start -0.12065 -0.2794)
			(end 0.12065 -0.2794)
			(stroke
				(width 0.1)
				(type default)
			)
			(layer "F.Fab")
		)
		(fp_line
			(start -0.12065 -0.305054)
			(end -0.12065 -0.2794)
			(stroke
				(width 0.1)
				(type default)
			)
			(layer "F.Fab")
		)
		(fp_line
			(start -0.67945 0.3048)
			(end -0.67945 -0.305054)
			(stroke
				(width 0.1)
				(type default)
			)
			(layer "F.Fab")
		)
		(fp_line
			(start -0.67945 -0.305054)
			(end -0.12065 -0.305054)
			(stroke
				(width 0.1)
				(type default)
			)
			(layer "F.Fab")
		)
		(pad "1" smd circle
			(at -0.40005 0 180)
			(size 0 0)
			(layers "F.Cu" "F.Mask" "F.Paste")
			(net "P3V3_AUX")
		)
		(pad "2" smd circle
			(at 0.40005 0 180)
			(size 0 0)
			(layers "F.Cu" "F.Mask" "F.Paste")
			(net "HP_LVC3_OCP_V3_2_PRSNT2_N")
		)
	)
	(footprint ""
		(layer "F.Cu")
		(at 195.00088 -112.613948 -90)
		(property "Reference" "OSC2"
			(at 2.15773 2.276602 0)
			(unlocked yes)
			(layer "F.SilkS")
			(effects
				(font
					(size 0.7874 0.5842)
					(thickness 0.1524)
				)
				(justify left)
			)
		)
		(property "Value" ""
			(at 0 0 270)
			(layer "F.Fab")
			(effects
				(font
					(size 1.27 1.27)
				)
			)
		)
		(duplicate_pad_numbers_are_jumpers no)
		(fp_line
			(start -1.299972 1.599946)
			(end -1.299972 -1.599946)
			(stroke
				(width 0.1524)
				(type default)
			)
			(layer "F.SilkS")
		)
		(fp_line
			(start 1.299972 1.599946)
			(end -1.299972 1.599946)
			(stroke
				(width 0.1524)
				(type default)
			)
			(layer "F.SilkS")
		)
		(fp_line
			(start -1.299972 -1.599946)
			(end 1.299972 -1.599946)
			(stroke
				(width 0.1524)
				(type default)
			)
			(layer "F.SilkS")
		)
		(fp_line
			(start 1.299972 -1.599946)
			(end 1.299972 1.599946)
			(stroke
				(width 0.1524)
				(type default)
			)
			(layer "F.SilkS")
		)
		(fp_poly
			(pts
				(xy -2.4892 -1.26492) (xy -1.4732 -0.75692) (xy -2.4892 -0.24892)
			)
			(stroke
				(width 0)
				(type default)
			)
			(fill yes)
			(layer "F.SilkS")
		)
		(fp_line
			(start -1.050036 1.299972)
			(end -1.050036 -1.299972)
			(stroke
				(width 0.1)
				(type default)
			)
			(layer "F.Fab")
		)
		(fp_line
			(start 1.050036 1.299972)
			(end -1.050036 1.299972)
			(stroke
				(width 0.1)
				(type default)
			)
			(layer "F.Fab")
		)
		(fp_line
			(start -1.050036 -1.299972)
			(end 1.050036 -1.299972)
			(stroke
				(width 0.1)
				(type default)
			)
			(layer "F.Fab")
		)
		(fp_line
			(start 1.050036 -1.299972)
			(end 1.050036 1.299972)
			(stroke
				(width 0.1)
				(type default)
			)
			(layer "F.Fab")
		)
		(fp_poly
			(pts
				(xy -2.4892 -0.24892) (xy -2.4892 -1.26492) (xy -1.4732 -0.75692)
			)
			(stroke
				(width 0)
				(type default)
			)
			(fill yes)
			(layer "F.Fab")
		)
		(pad "1" smd rect
			(at -0.649986 -0.849884 270)
			(size 1.016 1.2192)
			(layers "F.Cu" "F.Mask" "F.Paste")
			(net "PU_CLK25M_OSC_FPGA_EN")
		)
		(pad "2" smd rect
			(at -0.649986 0.849884 270)
			(size 1.016 1.2192)
			(layers "F.Cu" "F.Mask" "F.Paste")
			(net "GND")
		)
		(pad "3" smd rect
			(at 0.649986 0.849884 270)
			(size 1.016 1.2192)
			(layers "F.Cu" "F.Mask" "F.Paste")
			(net "CLK_25M_OSC_FPGA_R")
		)
		(pad "4" smd rect
			(at 0.649986 -0.849884 270)
			(size 1.016 1.2192)
			(layers "F.Cu" "F.Mask" "F.Paste")
			(net "P3V3_AUX")
		)
	)
)
